(kicad_pcb
	(version 20260206)
	(generator "pcbnew")
	(generator_version "10.0")
	(general
		(thickness 1.6)
		(legacy_teardrops no)
	)
	(paper "A4")
	(title_block
		(title "04192023_DAF0TMB3IC0_F0TG_MB_C_brd_V02_OCP.brd")
		(comment 1 "Grand Teton / footprints 403-409 of 8354")
	)
	(layers
		(0 "F.Cu" signal "TOP")
		(4 "In1.Cu" signal "GND")
		(6 "In2.Cu" signal "IN1")
		(8 "In3.Cu" signal "GND1")
		(10 "In4.Cu" signal "IN2")
		(12 "In5.Cu" signal "GND2")
		(14 "In6.Cu" signal "IN3")
		(16 "In7.Cu" signal "GND3")
		(18 "In8.Cu" signal "VCC")
		(20 "In9.Cu" signal "VCC1")
		(22 "In10.Cu" signal "GND4")
		(24 "In11.Cu" signal "IN4")
		(26 "In12.Cu" signal "GND5")
		(28 "In13.Cu" signal "IN5")
		(30 "In14.Cu" signal "GND6")
		(32 "In15.Cu" signal "IN6")
		(34 "In16.Cu" signal "GND7")
		(2 "B.Cu" signal "BOTTOM")
		(9 "F.Adhes" user "F.Adhesive")
		(11 "B.Adhes" user "B.Adhesive")
		(13 "F.Paste" user "Package Geometry/Pastemask Top")
		(15 "B.Paste" user "Package Geometry/Pastemask Bottom")
		(5 "F.SilkS" user "Ref Des/Silkscreen Top")
		(7 "B.SilkS" user "Ref Des/Silkscreen Bottom")
		(1 "F.Mask" user "Board Geometry/Soldermask Top")
		(3 "B.Mask" user "Board Geometry/Soldermask Bottom")
		(17 "Dwgs.User" user "User.Drawings")
		(19 "Cmts.User" user "User.Comments")
		(21 "Eco1.User" user "User.Eco1")
		(23 "Eco2.User" user "User.Eco2")
		(25 "Edge.Cuts" user "Board Geometry/Outline")
		(27 "Margin" user)
		(31 "F.CrtYd" user "Package Geometry/Place Bound Top")
		(29 "B.CrtYd" user "Package Geometry/Place Bound Bottom")
		(35 "F.Fab" user "Ref Des/Assembly Top")
		(33 "B.Fab" user "Ref Des/Assembly Bottom")
	)
	(footprint ""
		(layer "F.Cu")
		(at 125.38837 -32.751268)
		(property "Reference" "C6019"
			(at 0 0 0)
			(layer "F.SilkS")
			(hide yes)
			(effects
				(font
					(size 1.27 1.27)
				)
			)
		)
		(property "Value" ""
			(at 0 0 0)
			(layer "F.Fab")
			(effects
				(font
					(size 1.27 1.27)
				)
			)
		)
		(duplicate_pad_numbers_are_jumpers no)
		(fp_line
			(start -0.40005 -0.4064)
			(end 0.40005 -0.4064)
			(stroke
				(width 0.1524)
				(type default)
			)
			(layer "F.SilkS")
		)
		(fp_line
			(start 0.40005 0.4064)
			(end -0.40005 0.4064)
			(stroke
				(width 0.1524)
				(type default)
			)
			(layer "F.SilkS")
		)
		(fp_line
			(start -0.6858 -0.3048)
			(end -0.1016 -0.3048)
			(stroke
				(width 0.1)
				(type default)
			)
			(layer "F.Fab")
		)
		(fp_line
			(start -0.6858 0.3048)
			(end -0.6858 -0.3048)
			(stroke
				(width 0.1)
				(type default)
			)
			(layer "F.Fab")
		)
		(fp_line
			(start -0.1016 -0.3048)
			(end -0.1016 -0.2794)
			(stroke
				(width 0.1)
				(type default)
			)
			(layer "F.Fab")
		)
		(fp_line
			(start -0.1016 -0.2794)
			(end 0.1016 -0.2794)
			(stroke
				(width 0.1)
				(type default)
			)
			(layer "F.Fab")
		)
		(fp_line
			(start -0.1016 0.2794)
			(end -0.1016 0.3048)
			(stroke
				(width 0.1)
				(type default)
			)
			(layer "F.Fab")
		)
		(fp_line
			(start -0.1016 0.3048)
			(end -0.6858 0.3048)
			(stroke
				(width 0.1)
				(type default)
			)
			(layer "F.Fab")
		)
		(fp_line
			(start 0.1016 -0.3048)
			(end 0.6858 -0.3048)
			(stroke
				(width 0.1)
				(type default)
			)
			(layer "F.Fab")
		)
		(fp_line
			(start 0.1016 -0.2794)
			(end 0.1016 -0.3048)
			(stroke
				(width 0.1)
				(type default)
			)
			(layer "F.Fab")
		)
		(fp_line
			(start 0.1016 0.2794)
			(end -0.1016 0.2794)
			(stroke
				(width 0.1)
				(type default)
			)
			(layer "F.Fab")
		)
		(fp_line
			(start 0.1016 0.3048)
			(end 0.1016 0.2794)
			(stroke
				(width 0.1)
				(type default)
			)
			(layer "F.Fab")
		)
		(fp_line
			(start 0.6858 -0.3048)
			(end 0.6858 0.3048)
			(stroke
				(width 0.1)
				(type default)
			)
			(layer "F.Fab")
		)
		(fp_line
			(start 0.6858 0.3048)
			(end 0.1016 0.3048)
			(stroke
				(width 0.1)
				(type default)
			)
			(layer "F.Fab")
		)
		(pad "1" smd rect
			(at -0.40005 0 180)
			(size 0.4572 0.508)
			(layers "F.Cu" "F.Mask" "F.Paste")
			(net "USB3_CPU0_BMC_RX_DP")
		)
		(pad "2" smd rect
			(at 0.40005 0 180)
			(size 0.4572 0.508)
			(layers "F.Cu" "F.Mask" "F.Paste")
			(net "USB3_CPU0_BMC_RX_C1_DP")
		)
	)
	(footprint ""
		(layer "F.Cu")
		(at 308.379876 -70.098412 90)
		(property "Reference" "D6000"
			(at -3.75158 -1.438148 90)
			(unlocked yes)
			(layer "F.SilkS")
			(effects
				(font
					(size 0.7874 0.5842)
					(thickness 0.1524)
				)
				(justify left)
			)
		)
		(property "Value" ""
			(at 0 0 90)
			(layer "F.Fab")
			(effects
				(font
					(size 1.27 1.27)
				)
			)
		)
		(duplicate_pad_numbers_are_jumpers no)
		(fp_line
			(start 1.16078 -0.4826)
			(end 1.16078 0.4826)
			(stroke
				(width 0.1524)
				(type default)
			)
			(layer "F.SilkS")
		)
		(fp_line
			(start 1.03378 -0.4826)
			(end 1.03378 0.4826)
			(stroke
				(width 0.1524)
				(type default)
			)
			(layer "F.SilkS")
		)
		(fp_line
			(start 0.90678 -0.4826)
			(end 0.90678 0.4826)
			(stroke
				(width 0.1524)
				(type default)
			)
			(layer "F.SilkS")
		)
		(fp_line
			(start -0.64008 -0.4826)
			(end 1.16078 -0.4826)
			(stroke
				(width 0.1524)
				(type default)
			)
			(layer "F.SilkS")
		)
		(fp_line
			(start -0.79248 -0.4826)
			(end 1.03378 -0.4826)
			(stroke
				(width 0.1524)
				(type default)
			)
			(layer "F.SilkS")
		)
		(fp_line
			(start -0.89408 -0.4826)
			(end 0.90678 -0.4826)
			(stroke
				(width 0.1524)
				(type default)
			)
			(layer "F.SilkS")
		)
		(fp_line
			(start 1.16078 0.4826)
			(end -0.64008 0.4826)
			(stroke
				(width 0.1524)
				(type default)
			)
			(layer "F.SilkS")
		)
		(fp_line
			(start 1.03378 0.4826)
			(end -0.79248 0.4826)
			(stroke
				(width 0.1524)
				(type default)
			)
			(layer "F.SilkS")
		)
		(fp_line
			(start 0.90678 0.4826)
			(end -0.90678 0.4826)
			(stroke
				(width 0.1524)
				(type default)
			)
			(layer "F.SilkS")
		)
		(fp_line
			(start -0.90678 0.4826)
			(end -0.90678 -0.4699)
			(stroke
				(width 0.1524)
				(type default)
			)
			(layer "F.SilkS")
		)
		(fp_line
			(start 0.499872 -0.249936)
			(end 0.499872 0.249936)
			(stroke
				(width 0.1)
				(type default)
			)
			(layer "F.Fab")
		)
		(fp_line
			(start -0.499872 -0.249936)
			(end 0.499872 -0.249936)
			(stroke
				(width 0.1)
				(type default)
			)
			(layer "F.Fab")
		)
		(fp_line
			(start 0.499872 0.249936)
			(end -0.499872 0.249936)
			(stroke
				(width 0.1)
				(type default)
			)
			(layer "F.Fab")
		)
		(fp_line
			(start -0.499872 0.249936)
			(end -0.499872 -0.249936)
			(stroke
				(width 0.1)
				(type default)
			)
			(layer "F.Fab")
		)
		(pad "A" smd rect
			(at -0.47498 0 90)
			(size 0.6096 0.7112)
			(layers "F.Cu" "F.Mask" "F.Paste")
			(net "LED_PWRGD_P1V2_AUX")
		)
		(pad "C" smd rect
			(at 0.47498 0 90)
			(size 0.6096 0.7112)
			(layers "F.Cu" "F.Mask" "F.Paste")
			(net "LED_PWRGD_P1V2_AUX_D")
		)
	)
	(footprint ""
		(layer "F.Cu")
		(at 437.09463 -425.534836 90)
		(property "Reference" "R651"
			(at 0 0 90)
			(layer "F.SilkS")
			(hide yes)
			(effects
				(font
					(size 1.27 1.27)
				)
			)
		)
		(property "Value" ""
			(at 0 0 90)
			(layer "F.Fab")
			(effects
				(font
					(size 1.27 1.27)
				)
			)
		)
		(duplicate_pad_numbers_are_jumpers no)
		(fp_line
			(start 0.7874 -0.4064)
			(end 0.7874 0.4064)
			(stroke
				(width 0.1524)
				(type default)
			)
			(layer "F.SilkS")
		)
		(fp_line
			(start -0.7874 -0.4064)
			(end 0.7874 -0.4064)
			(stroke
				(width 0.1524)
				(type default)
			)
			(layer "F.SilkS")
		)
		(fp_line
			(start 0.7874 0.4064)
			(end -0.7874 0.4064)
			(stroke
				(width 0.1524)
				(type default)
			)
			(layer "F.SilkS")
		)
		(fp_line
			(start -0.7874 0.4064)
			(end -0.7874 -0.4064)
			(stroke
				(width 0.1524)
				(type default)
			)
			(layer "F.SilkS")
		)
		(fp_line
			(start -0.12065 -0.305054)
			(end -0.12065 -0.2794)
			(stroke
				(width 0.1)
				(type default)
			)
			(layer "F.Fab")
		)
		(fp_line
			(start -0.67945 -0.305054)
			(end -0.12065 -0.305054)
			(stroke
				(width 0.1)
				(type default)
			)
			(layer "F.Fab")
		)
		(fp_line
			(start 0.67945 -0.3048)
			(end 0.67945 0.3048)
			(stroke
				(width 0.1)
				(type default)
			)
			(layer "F.Fab")
		)
		(fp_line
			(start 0.12065 -0.3048)
			(end 0.67945 -0.3048)
			(stroke
				(width 0.1)
				(type default)
			)
			(layer "F.Fab")
		)
		(fp_line
			(start 0.12065 -0.2794)
			(end 0.12065 -0.3048)
			(stroke
				(width 0.1)
				(type default)
			)
			(layer "F.Fab")
		)
		(fp_line
			(start -0.12065 -0.2794)
			(end 0.12065 -0.2794)
			(stroke
				(width 0.1)
				(type default)
			)
			(layer "F.Fab")
		)
		(fp_line
			(start 0.120396 0.2794)
			(end -0.12065 0.2794)
			(stroke
				(width 0.1)
				(type default)
			)
			(layer "F.Fab")
		)
		(fp_line
			(start -0.12065 0.2794)
			(end -0.12065 0.3048)
			(stroke
				(width 0.1)
				(type default)
			)
			(layer "F.Fab")
		)
		(fp_line
			(start 0.67945 0.3048)
			(end 0.120396 0.3048)
			(stroke
				(width 0.1)
				(type default)
			)
			(layer "F.Fab")
		)
		(fp_line
			(start 0.120396 0.3048)
			(end 0.120396 0.2794)
			(stroke
				(width 0.1)
				(type default)
			)
			(layer "F.Fab")
		)
		(fp_line
			(start -0.12065 0.3048)
			(end -0.67945 0.3048)
			(stroke
				(width 0.1)
				(type default)
			)
			(layer "F.Fab")
		)
		(fp_line
			(start -0.67945 0.3048)
			(end -0.67945 -0.305054)
			(stroke
				(width 0.1)
				(type default)
			)
			(layer "F.Fab")
		)
		(pad "1" smd circle
			(at -0.40005 0 90)
			(size 0 0)
			(layers "F.Cu" "F.Mask" "F.Paste")
			(net "P0V9_RETIMER_CPU0_EN")
		)
		(pad "2" smd circle
			(at 0.40005 0 90)
			(size 0 0)
			(layers "F.Cu" "F.Mask" "F.Paste")
			(net "P0V9_RETIMER_CPU0_EN0_R")
		)
	)
	(footprint ""
		(layer "F.Cu")
		(at 84.527644 -408.517344 -90)
		(property "Reference" "C6654"
			(at 0 0 270)
			(layer "F.SilkS")
			(hide yes)
			(effects
				(font
					(size 1.27 1.27)
				)
			)
		)
		(property "Value" ""
			(at 0 0 270)
			(layer "F.Fab")
			(effects
				(font
					(size 1.27 1.27)
				)
			)
		)
		(duplicate_pad_numbers_are_jumpers no)
		(fp_line
			(start -0.299974 0.150114)
			(end -0.299974 -0.150114)
			(stroke
				(width 0.1)
				(type default)
			)
			(layer "F.Fab")
		)
		(fp_line
			(start 0.299974 0.150114)
			(end -0.299974 0.150114)
			(stroke
				(width 0.1)
				(type default)
			)
			(layer "F.Fab")
		)
		(fp_line
			(start -0.299974 -0.150114)
			(end 0.299974 -0.150114)
			(stroke
				(width 0.1)
				(type default)
			)
			(layer "F.Fab")
		)
		(fp_line
			(start 0.299974 -0.150114)
			(end 0.299974 0.150114)
			(stroke
				(width 0.1)
				(type default)
			)
			(layer "F.Fab")
		)
		(pad "1" smd rect
			(at -0.2667 0 270)
			(size 0.3048 0.381)
			(layers "F.Cu" "F.Mask" "F.Paste")
			(net "P5E_CPU1_P0_TX_BUF_C_DN<12>")
		)
		(pad "2" smd rect
			(at 0.2667 0 270)
			(size 0.3048 0.381)
			(layers "F.Cu" "F.Mask" "F.Paste")
			(net "P5E_CPU1_P0_TX_BUF_DN<12>")
		)
	)
	(footprint ""
		(layer "F.Cu")
		(at 168.656 -434.869336 180)
		(property "Reference" "R2669"
			(at 0 0 180)
			(layer "F.SilkS")
			(hide yes)
			(effects
				(font
					(size 1.27 1.27)
				)
			)
		)
		(property "Value" ""
			(at 0 0 180)
			(layer "F.Fab")
			(effects
				(font
					(size 1.27 1.27)
				)
			)
		)
		(duplicate_pad_numbers_are_jumpers no)
		(fp_line
			(start 0.7874 0.4064)
			(end -0.7874 0.4064)
			(stroke
				(width 0.1524)
				(type default)
			)
			(layer "F.SilkS")
		)
		(fp_line
			(start 0.7874 -0.4064)
			(end 0.7874 0.4064)
			(stroke
				(width 0.1524)
				(type default)
			)
			(layer "F.SilkS")
		)
		(fp_line
			(start -0.7874 0.4064)
			(end -0.7874 -0.4064)
			(stroke
				(width 0.1524)
				(type default)
			)
			(layer "F.SilkS")
		)
		(fp_line
			(start -0.7874 -0.4064)
			(end 0.7874 -0.4064)
			(stroke
				(width 0.1524)
				(type default)
			)
			(layer "F.SilkS")
		)
		(fp_line
			(start 0.67945 0.3048)
			(end 0.120396 0.3048)
			(stroke
				(width 0.1)
				(type default)
			)
			(layer "F.Fab")
		)
		(fp_line
			(start 0.67945 -0.3048)
			(end 0.67945 0.3048)
			(stroke
				(width 0.1)
				(type default)
			)
			(layer "F.Fab")
		)
		(fp_line
			(start 0.12065 -0.2794)
			(end 0.12065 -0.3048)
			(stroke
				(width 0.1)
				(type default)
			)
			(layer "F.Fab")
		)
		(fp_line
			(start 0.12065 -0.3048)
			(end 0.67945 -0.3048)
			(stroke
				(width 0.1)
				(type default)
			)
			(layer "F.Fab")
		)
		(fp_line
			(start 0.120396 0.3048)
			(end 0.120396 0.2794)
			(stroke
				(width 0.1)
				(type default)
			)
			(layer "F.Fab")
		)
		(fp_line
			(start 0.120396 0.2794)
			(end -0.12065 0.2794)
			(stroke
				(width 0.1)
				(type default)
			)
			(layer "F.Fab")
		)
		(fp_line
			(start -0.12065 0.3048)
			(end -0.67945 0.3048)
			(stroke
				(width 0.1)
				(type default)
			)
			(layer "F.Fab")
		)
		(fp_line
			(start -0.12065 0.2794)
			(end -0.12065 0.3048)
			(stroke
				(width 0.1)
				(type default)
			)
			(layer "F.Fab")
		)
		(fp_line
			(start -0.12065 -0.2794)
			(end 0.12065 -0.2794)
			(stroke
				(width 0.1)
				(type default)
			)
			(layer "F.Fab")
		)
		(fp_line
			(start -0.12065 -0.305054)
			(end -0.12065 -0.2794)
			(stroke
				(width 0.1)
				(type default)
			)
			(layer "F.Fab")
		)
		(fp_line
			(start -0.67945 0.3048)
			(end -0.67945 -0.305054)
			(stroke
				(width 0.1)
				(type default)
			)
			(layer "F.Fab")
		)
		(fp_line
			(start -0.67945 -0.305054)
			(end -0.12065 -0.305054)
			(stroke
				(width 0.1)
				(type default)
			)
			(layer "F.Fab")
		)
		(pad "1" smd circle
			(at -0.40005 0 180)
			(size 0 0)
			(layers "F.Cu" "F.Mask" "F.Paste")
			(net "P3V3_AUX")
		)
		(pad "2" smd circle
			(at 0.40005 0 180)
			(size 0 0)
			(layers "F.Cu" "F.Mask" "F.Paste")
			(net "SMB_BMC_SWB_BUF_R_SDA")
		)
	)
	(footprint ""
		(layer "F.Cu")
		(at 198.247 -94.234)
		(property "Reference" "R8091"
			(at 0 0 0)
			(layer "F.SilkS")
			(hide yes)
			(effects
				(font
					(size 1.27 1.27)
				)
			)
		)
		(property "Value" ""
			(at 0 0 0)
			(layer "F.Fab")
			(effects
				(font
					(size 1.27 1.27)
				)
			)
		)
		(duplicate_pad_numbers_are_jumpers no)
		(fp_line
			(start -0.7874 -0.4064)
			(end 0.7874 -0.4064)
			(stroke
				(width 0.1524)
				(type default)
			)
			(layer "F.SilkS")
		)
		(fp_line
			(start -0.7874 0.4064)
			(end -0.7874 -0.4064)
			(stroke
				(width 0.1524)
				(type default)
			)
			(layer "F.SilkS")
		)
		(fp_line
			(start 0.7874 -0.4064)
			(end 0.7874 0.4064)
			(stroke
				(width 0.1524)
				(type default)
			)
			(layer "F.SilkS")
		)
		(fp_line
			(start 0.7874 0.4064)
			(end -0.7874 0.4064)
			(stroke
				(width 0.1524)
				(type default)
			)
			(layer "F.SilkS")
		)
		(fp_line
			(start -0.67945 -0.305054)
			(end -0.12065 -0.305054)
			(stroke
				(width 0.1)
				(type default)
			)
			(layer "F.Fab")
		)
		(fp_line
			(start -0.67945 0.3048)
			(end -0.67945 -0.305054)
			(stroke
				(width 0.1)
				(type default)
			)
			(layer "F.Fab")
		)
		(fp_line
			(start -0.12065 -0.305054)
			(end -0.12065 -0.2794)
			(stroke
				(width 0.1)
				(type default)
			)
			(layer "F.Fab")
		)
		(fp_line
			(start -0.12065 -0.2794)
			(end 0.12065 -0.2794)
			(stroke
				(width 0.1)
				(type default)
			)
			(layer "F.Fab")
		)
		(fp_line
			(start -0.12065 0.2794)
			(end -0.12065 0.3048)
			(stroke
				(width 0.1)
				(type default)
			)
			(layer "F.Fab")
		)
		(fp_line
			(start -0.12065 0.3048)
			(end -0.67945 0.3048)
			(stroke
				(width 0.1)
				(type default)
			)
			(layer "F.Fab")
		)
		(fp_line
			(start 0.120396 0.2794)
			(end -0.12065 0.2794)
			(stroke
				(width 0.1)
				(type default)
			)
			(layer "F.Fab")
		)
		(fp_line
			(start 0.120396 0.3048)
			(end 0.120396 0.2794)
			(stroke
				(width 0.1)
				(type default)
			)
			(layer "F.Fab")
		)
		(fp_line
			(start 0.12065 -0.3048)
			(end 0.67945 -0.3048)
			(stroke
				(width 0.1)
				(type default)
			)
			(layer "F.Fab")
		)
		(fp_line
			(start 0.12065 -0.2794)
			(end 0.12065 -0.3048)
			(stroke
				(width 0.1)
				(type default)
			)
			(layer "F.Fab")
		)
		(fp_line
			(start 0.67945 -0.3048)
			(end 0.67945 0.3048)
			(stroke
				(width 0.1)
				(type default)
			)
			(layer "F.Fab")
		)
		(fp_line
			(start 0.67945 0.3048)
			(end 0.120396 0.3048)
			(stroke
				(width 0.1)
				(type default)
			)
			(layer "F.Fab")
		)
		(pad "1" smd circle
			(at -0.40005 0)
			(size 0 0)
			(layers "F.Cu" "F.Mask" "F.Paste")
			(net "P3V3_AUX")
		)
		(pad "2" smd circle
			(at 0.40005 0)
			(size 0 0)
			(layers "F.Cu" "F.Mask" "F.Paste")
			(net "PWRGD_CHGL_CPU1_R1")
		)
	)
	(footprint ""
		(layer "F.Cu")
		(at 46.096428 -399.41246)
		(property "Reference" "R6705"
			(at 0 0 0)
			(layer "F.SilkS")
			(hide yes)
			(effects
				(font
					(size 1.27 1.27)
				)
			)
		)
		(property "Value" ""
			(at 0 0 0)
			(layer "F.Fab")
			(effects
				(font
					(size 1.27 1.27)
				)
			)
		)
		(duplicate_pad_numbers_are_jumpers no)
		(fp_line
			(start -1.2954 -0.5842)
			(end 1.2954 -0.5842)
			(stroke
				(width 0.1524)
				(type default)
			)
			(layer "F.SilkS")
		)
		(fp_line
			(start -1.2954 0.5842)
			(end -1.2954 -0.5842)
			(stroke
				(width 0.1524)
				(type default)
			)
			(layer "F.SilkS")
		)
		(fp_line
			(start 1.2954 -0.5842)
			(end 1.2954 0.5842)
			(stroke
				(width 0.1524)
				(type default)
			)
			(layer "F.SilkS")
		)
		(fp_line
			(start 1.2954 0.5842)
			(end -1.2954 0.5842)
			(stroke
				(width 0.1524)
				(type default)
			)
			(layer "F.SilkS")
		)
		(fp_line
			(start -1.1938 -0.406654)
			(end -0.8636 -0.406654)
			(stroke
				(width 0.1)
				(type default)
			)
			(layer "F.Fab")
		)
		(fp_line
			(start -1.1938 0.4064)
			(end -1.1938 -0.406654)
			(stroke
				(width 0.1)
				(type default)
			)
			(layer "F.Fab")
		)
		(fp_line
			(start -0.8636 -0.4572)
			(end 0.8636 -0.4572)
			(stroke
				(width 0.1)
				(type default)
			)
			(layer "F.Fab")
		)
		(fp_line
			(start -0.8636 -0.406654)
			(end -0.8636 -0.4572)
			(stroke
				(width 0.1)
				(type default)
			)
			(layer "F.Fab")
		)
		(fp_line
			(start -0.8636 0.4064)
			(end -1.1938 0.4064)
			(stroke
				(width 0.1)
				(type default)
			)
			(layer "F.Fab")
		)
		(fp_line
			(start -0.8636 0.4318)
			(end -0.8636 0.4064)
			(stroke
				(width 0.1)
				(type default)
			)
			(layer "F.Fab")
		)
		(fp_line
			(start -0.8636 0.4572)
			(end -0.8636 0.4318)
			(stroke
				(width 0.1)
				(type default)
			)
			(layer "F.Fab")
		)
		(fp_line
			(start 0.8636 -0.4572)
			(end 0.8636 -0.406654)
			(stroke
				(width 0.1)
				(type default)
			)
			(layer "F.Fab")
		)
		(fp_line
			(start 0.8636 -0.406654)
			(end 1.1938 -0.406654)
			(stroke
				(width 0.1)
				(type default)
			)
			(layer "F.Fab")
		)
		(fp_line
			(start 0.8636 0.4064)
			(end 0.8636 0.4572)
			(stroke
				(width 0.1)
				(type default)
			)
			(layer "F.Fab")
		)
		(fp_line
			(start 0.8636 0.4572)
			(end -0.8636 0.4572)
			(stroke
				(width 0.1)
				(type default)
			)
			(layer "F.Fab")
		)
		(fp_line
			(start 1.1938 -0.406654)
			(end 1.1938 0.4064)
			(stroke
				(width 0.1)
				(type default)
			)
			(layer "F.Fab")
		)
		(fp_line
			(start 1.1938 0.4064)
			(end 0.8636 0.4064)
			(stroke
				(width 0.1)
				(type default)
			)
			(layer "F.Fab")
		)
		(pad "1" smd rect
			(at -0.7366 0 270)
			(size 0.7112 0.8128)
			(layers "F.Cu" "F.Mask" "F.Paste")
			(net "P0V9_CPU1_RT0_2A_2D")
		)
		(pad "2" smd rect
			(at 0.7366 0 270)
			(size 0.7112 0.8128)
			(layers "F.Cu" "F.Mask" "F.Paste")
			(net "P0V9_CPU1_RT0_2A")
		)
	)
)
